# S9S_MB_2U (Grand Teton) — schematic netlist excerpt (pin names and nets, part order shuffled) for the footprints in the layout excerpt that follows; sources: Cadence DE-HDL packaged netlist, KiCad conversion of 03242023_DA0F0TMBIJ0_F0T_Motherboard_J_brd_V01_OCP.brd

C848  Q_CAP_DIFFBUS  DIFF BUS_0.22UF 6.3V 20% X6S  pkg C0201  page 174 : \1\ = P5E_CPU0_PE1_TX_C_DN<10> ; \2\ = P5E_CPU0_PE1_TX_DN<10>
R4802  Q_RES  0 5% CHIP  pkg 0402LF  page 227 : A = PRSNT_CABLE_GPU_A3_ISO_N ; B = PRSNT_CABLE_GPU_A3_ISO_R_N
PC1371  Q_CAP  0.1UF 25V 10% X7R  pkg 0402  page 297 : A = GND ; B = PVCCD_HV_CPU1_VREF

(kicad_pcb
	(version 20260206)
	(generator "pcbnew")
	(generator_version "10.0")
	(general
		(thickness 1.6)
		(legacy_teardrops no)
	)
	(paper "A4")
	(title_block
		(title "03242023_DA0F0TMBIJ0_F0T_Motherboard_J_brd_V01_OCP.brd")
		(comment 1 "Grand Teton / footprints 2095-2097 of 6105")
	)
	(layers
		(0 "F.Cu" signal "TOP")
		(4 "In1.Cu" signal "GND")
		(6 "In2.Cu" signal "IN1")
		(8 "In3.Cu" signal "GND1")
		(10 "In4.Cu" signal "IN2")
		(12 "In5.Cu" signal "GND2")
		(14 "In6.Cu" signal "IN3")
		(16 "In7.Cu" signal "GND3")
		(18 "In8.Cu" signal "VCC")
		(20 "In9.Cu" signal "VCC1")
		(22 "In10.Cu" signal "GND4")
		(24 "In11.Cu" signal "IN4")
		(26 "In12.Cu" signal "GND5")
		(28 "In13.Cu" signal "IN5")
		(30 "In14.Cu" signal "GND6")
		(32 "In15.Cu" signal "IN6")
		(34 "In16.Cu" signal "GND7")
		(2 "B.Cu" signal "BOTTOM")
		(9 "F.Adhes" user "F.Adhesive")
		(11 "B.Adhes" user "B.Adhesive")
		(13 "F.Paste" user "Package Geometry/Pastemask Top")
		(15 "B.Paste" user "Package Geometry/Pastemask Bottom")
		(5 "F.SilkS" user "Ref Des/Silkscreen Top")
		(7 "B.SilkS" user "Ref Des/Silkscreen Bottom")
		(1 "F.Mask" user "Board Geometry/Soldermask Top")
		(3 "B.Mask" user "Board Geometry/Soldermask Bottom")
		(17 "Dwgs.User" user "User.Drawings")
		(19 "Cmts.User" user "User.Comments")
		(21 "Eco1.User" user "User.Eco1")
		(23 "Eco2.User" user "User.Eco2")
		(25 "Edge.Cuts" user "Board Geometry/Outline")
		(27 "Margin" user)
		(31 "F.CrtYd" user "Package Geometry/Place Bound Top")
		(29 "B.CrtYd" user "Package Geometry/Place Bound Bottom")
		(35 "F.Fab" user "Ref Des/Assembly Top")
		(33 "B.Fab" user "Ref Des/Assembly Bottom")
	)
	(footprint ""
		(layer "F.Cu")
		(at 50.317654 -162.280854)
		(property "Reference" "PC1371"
			(at 0 0 0)
			(layer "F.SilkS")
			(hide yes)
			(effects
				(font
					(size 1.27 1.27)
				)
			)
		)
		(property "Value" ""
			(at 0 0 0)
			(layer "F.Fab")
			(effects
				(font
					(size 1.27 1.27)
				)
			)
		)
		(duplicate_pad_numbers_are_jumpers no)
		(fp_line
			(start -0.7874 -0.4064)
			(end 0.7874 -0.4064)
			(stroke
				(width 0.1524)
				(type default)
			)
			(layer "F.SilkS")
		)
		(fp_line
			(start -0.7874 0.4064)
			(end -0.7874 -0.4064)
			(stroke
				(width 0.1524)
				(type default)
			)
			(layer "F.SilkS")
		)
		(fp_line
			(start 0.7874 -0.4064)
			(end 0.7874 0.4064)
			(stroke
				(width 0.1524)
				(type default)
			)
			(layer "F.SilkS")
		)
		(fp_line
			(start 0.7874 0.4064)
			(end -0.7874 0.4064)
			(stroke
				(width 0.1524)
				(type default)
			)
			(layer "F.SilkS")
		)
		(fp_line
			(start -0.67945 -0.305054)
			(end -0.12065 -0.305054)
			(stroke
				(width 0.1)
				(type default)
			)
			(layer "F.Fab")
		)
		(fp_line
			(start -0.67945 0.3048)
			(end -0.67945 -0.305054)
			(stroke
				(width 0.1)
				(type default)
			)
			(layer "F.Fab")
		)
		(fp_line
			(start -0.12065 -0.305054)
			(end -0.12065 -0.2794)
			(stroke
				(width 0.1)
				(type default)
			)
			(layer "F.Fab")
		)
		(fp_line
			(start -0.12065 -0.2794)
			(end 0.12065 -0.2794)
			(stroke
				(width 0.1)
				(type default)
			)
			(layer "F.Fab")
		)
		(fp_line
			(start -0.12065 0.2794)
			(end -0.12065 0.3048)
			(stroke
				(width 0.1)
				(type default)
			)
			(layer "F.Fab")
		)
		(fp_line
			(start -0.12065 0.3048)
			(end -0.67945 0.3048)
			(stroke
				(width 0.1)
				(type default)
			)
			(layer "F.Fab")
		)
		(fp_line
			(start 0.120396 0.2794)
			(end -0.12065 0.2794)
			(stroke
				(width 0.1)
				(type default)
			)
			(layer "F.Fab")
		)
		(fp_line
			(start 0.120396 0.3048)
			(end 0.120396 0.2794)
			(stroke
				(width 0.1)
				(type default)
			)
			(layer "F.Fab")
		)
		(fp_line
			(start 0.12065 -0.3048)
			(end 0.67945 -0.3048)
			(stroke
				(width 0.1)
				(type default)
			)
			(layer "F.Fab")
		)
		(fp_line
			(start 0.12065 -0.2794)
			(end 0.12065 -0.3048)
			(stroke
				(width 0.1)
				(type default)
			)
			(layer "F.Fab")
		)
		(fp_line
			(start 0.67945 -0.3048)
			(end 0.67945 0.3048)
			(stroke
				(width 0.1)
				(type default)
			)
			(layer "F.Fab")
		)
		(fp_line
			(start 0.67945 0.3048)
			(end 0.120396 0.3048)
			(stroke
				(width 0.1)
				(type default)
			)
			(layer "F.Fab")
		)
		(pad "1" smd circle
			(at -0.40005 0)
			(size 0 0)
			(layers "F.Cu" "F.Mask" "F.Paste")
			(net "GND")
		)
		(pad "2" smd circle
			(at 0.40005 0)
			(size 0 0)
			(layers "F.Cu" "F.Mask" "F.Paste")
			(net "PVCCD_HV_CPU1_VREF")
		)
	)
	(footprint ""
		(layer "F.Cu")
		(at 15.494 -426.1358 -90)
		(property "Reference" "R4802"
			(at 0 0 270)
			(layer "F.SilkS")
			(hide yes)
			(effects
				(font
					(size 1.27 1.27)
				)
			)
		)
		(property "Value" ""
			(at 0 0 270)
			(layer "F.Fab")
			(effects
				(font
					(size 1.27 1.27)
				)
			)
		)
		(duplicate_pad_numbers_are_jumpers no)
		(fp_line
			(start -0.7874 0.4064)
			(end -0.7874 -0.4064)
			(stroke
				(width 0.1524)
				(type default)
			)
			(layer "F.SilkS")
		)
		(fp_line
			(start 0.7874 0.4064)
			(end -0.7874 0.4064)
			(stroke
				(width 0.1524)
				(type default)
			)
			(layer "F.SilkS")
		)
		(fp_line
			(start -0.7874 -0.4064)
			(end 0.7874 -0.4064)
			(stroke
				(width 0.1524)
				(type default)
			)
			(layer "F.SilkS")
		)
		(fp_line
			(start 0.7874 -0.4064)
			(end 0.7874 0.4064)
			(stroke
				(width 0.1524)
				(type default)
			)
			(layer "F.SilkS")
		)
		(fp_line
			(start -0.67945 0.3048)
			(end -0.67945 -0.305054)
			(stroke
				(width 0.1)
				(type default)
			)
			(layer "F.Fab")
		)
		(fp_line
			(start -0.12065 0.3048)
			(end -0.67945 0.3048)
			(stroke
				(width 0.1)
				(type default)
			)
			(layer "F.Fab")
		)
		(fp_line
			(start 0.120396 0.3048)
			(end 0.120396 0.2794)
			(stroke
				(width 0.1)
				(type default)
			)
			(layer "F.Fab")
		)
		(fp_line
			(start 0.67945 0.3048)
			(end 0.120396 0.3048)
			(stroke
				(width 0.1)
				(type default)
			)
			(layer "F.Fab")
		)
		(fp_line
			(start -0.12065 0.2794)
			(end -0.12065 0.3048)
			(stroke
				(width 0.1)
				(type default)
			)
			(layer "F.Fab")
		)
		(fp_line
			(start 0.120396 0.2794)
			(end -0.12065 0.2794)
			(stroke
				(width 0.1)
				(type default)
			)
			(layer "F.Fab")
		)
		(fp_line
			(start -0.12065 -0.2794)
			(end 0.12065 -0.2794)
			(stroke
				(width 0.1)
				(type default)
			)
			(layer "F.Fab")
		)
		(fp_line
			(start 0.12065 -0.2794)
			(end 0.12065 -0.3048)
			(stroke
				(width 0.1)
				(type default)
			)
			(layer "F.Fab")
		)
		(fp_line
			(start 0.12065 -0.3048)
			(end 0.67945 -0.3048)
			(stroke
				(width 0.1)
				(type default)
			)
			(layer "F.Fab")
		)
		(fp_line
			(start 0.67945 -0.3048)
			(end 0.67945 0.3048)
			(stroke
				(width 0.1)
				(type default)
			)
			(layer "F.Fab")
		)
		(fp_line
			(start -0.67945 -0.305054)
			(end -0.12065 -0.305054)
			(stroke
				(width 0.1)
				(type default)
			)
			(layer "F.Fab")
		)
		(fp_line
			(start -0.12065 -0.305054)
			(end -0.12065 -0.2794)
			(stroke
				(width 0.1)
				(type default)
			)
			(layer "F.Fab")
		)
		(pad "1" smd circle
			(at -0.40005 0 270)
			(size 0 0)
			(layers "F.Cu" "F.Mask" "F.Paste")
			(net "PRSNT_CABLE_GPU_A3_ISO_N")
		)
		(pad "2" smd circle
			(at 0.40005 0 270)
			(size 0 0)
			(layers "F.Cu" "F.Mask" "F.Paste")
			(net "PRSNT_CABLE_GPU_A3_ISO_R_N")
		)
	)
	(footprint ""
		(layer "F.Cu")
		(at 403.985984 -17.612614 90)
		(property "Reference" "C848"
			(at 0 0 90)
			(layer "F.SilkS")
			(hide yes)
			(effects
				(font
					(size 1.27 1.27)
				)
			)
		)
		(property "Value" ""
			(at 0 0 90)
			(layer "F.Fab")
			(effects
				(font
					(size 1.27 1.27)
				)
			)
		)
		(duplicate_pad_numbers_are_jumpers no)
		(fp_line
			(start 0.299974 -0.150114)
			(end 0.299974 0.150114)
			(stroke
				(width 0.1)
				(type default)
			)
			(layer "F.Fab")
		)
		(fp_line
			(start -0.299974 -0.150114)
			(end 0.299974 -0.150114)
			(stroke
				(width 0.1)
				(type default)
			)
			(layer "F.Fab")
		)
		(fp_line
			(start 0.299974 0.150114)
			(end -0.299974 0.150114)
			(stroke
				(width 0.1)
				(type default)
			)
			(layer "F.Fab")
		)
		(fp_line
			(start -0.299974 0.150114)
			(end -0.299974 -0.150114)
			(stroke
				(width 0.1)
				(type default)
			)
			(layer "F.Fab")
		)
		(pad "1" smd rect
			(at -0.2667 0 90)
			(size 0.3048 0.381)
			(layers "F.Cu" "F.Mask" "F.Paste")
			(net "P5E_CPU0_PE1_TX_C_DN<10>")
		)
		(pad "2" smd rect
			(at 0.2667 0 90)
			(size 0.3048 0.381)
			(layers "F.Cu" "F.Mask" "F.Paste")
			(net "P5E_CPU0_PE1_TX_DN<10>")
		)
	)
)
